(kicad_pcb
	(version 20260206)
	(generator "pcbnew")
	(generator_version "10.0")
	(general
		(thickness 1.6)
		(legacy_teardrops no)
	)
	(paper "A4")
	(title_block
		(title "12092022_DA0F0TYB4D0_F0T_Panel_BD_Front_D_brd_v02_OCP.brd")
		(comment 1 "Grand Teton / footprints 1-2 of 128")
	)
	(layers
		(0 "F.Cu" signal "TOP")
		(4 "In1.Cu" signal "GND")
		(6 "In2.Cu" signal "GND1")
		(2 "B.Cu" signal "BOTTOM")
		(9 "F.Adhes" user "F.Adhesive")
		(11 "B.Adhes" user "B.Adhesive")
		(13 "F.Paste" user "Package Geometry/Pastemask Top")
		(15 "B.Paste" user "Package Geometry/Pastemask Bottom")
		(5 "F.SilkS" user "Ref Des/Silkscreen Top")
		(7 "B.SilkS" user "Ref Des/Silkscreen Bottom")
		(1 "F.Mask" user "Board Geometry/Soldermask Top")
		(3 "B.Mask" user "Board Geometry/Soldermask Bottom")
		(17 "Dwgs.User" user "User.Drawings")
		(19 "Cmts.User" user "User.Comments")
		(21 "Eco1.User" user "User.Eco1")
		(23 "Eco2.User" user "User.Eco2")
		(25 "Edge.Cuts" user "Board Geometry/Outline")
		(27 "Margin" user)
		(31 "F.CrtYd" user "Package Geometry/Place Bound Top")
		(29 "B.CrtYd" user "Package Geometry/Place Bound Bottom")
		(35 "F.Fab" user "Ref Des/Assembly Top")
		(33 "B.Fab" user "Ref Des/Assembly Bottom")
	)
	(footprint ""
		(layer "F.Cu")
		(at 32.004 -29.591)
		(property "Reference" "U7"
			(at -3.302 0.02667 0)
			(unlocked yes)
			(layer "F.SilkS")
			(effects
				(font
					(size 0.7874 0.5842)
					(thickness 0.1524)
				)
				(justify left)
			)
		)
		(property "Value" ""
			(at 0 0 0)
			(layer "F.Fab")
			(effects
				(font
					(size 1.27 1.27)
				)
			)
		)
		(duplicate_pad_numbers_are_jumpers no)
		(fp_line
			(start -1.738884 -1.549908)
			(end -1.738884 1.549908)
			(stroke
				(width 0.1524)
				(type default)
			)
			(layer "F.SilkS")
		)
		(fp_line
			(start -1.738884 1.549908)
			(end 1.738884 1.549908)
			(stroke
				(width 0.1524)
				(type default)
			)
			(layer "F.SilkS")
		)
		(fp_line
			(start -0.635508 -1.549908)
			(end -1.738884 -1.549908)
			(stroke
				(width 0.1524)
				(type default)
			)
			(layer "F.SilkS")
		)
		(fp_line
			(start 0 -0.9144)
			(end -0.635508 -1.549908)
			(stroke
				(width 0.1524)
				(type default)
			)
			(layer "F.SilkS")
		)
		(fp_line
			(start 0.635508 -1.549908)
			(end 0 -0.9144)
			(stroke
				(width 0.1524)
				(type default)
			)
			(layer "F.SilkS")
		)
		(fp_line
			(start 1.738884 -1.549908)
			(end 0.635508 -1.549908)
			(stroke
				(width 0.1524)
				(type default)
			)
			(layer "F.SilkS")
		)
		(fp_line
			(start 1.738884 1.549908)
			(end 1.738884 -1.549908)
			(stroke
				(width 0.1524)
				(type default)
			)
			(layer "F.SilkS")
		)
		(fp_poly
			(pts
				(xy -2.445766 -1.211326) (xy -1.923034 -0.94996) (xy -2.445766 -0.688594)
			)
			(stroke
				(width 0)
				(type default)
			)
			(fill yes)
			(layer "F.SilkS")
		)
		(fp_line
			(start -0.849884 -1.549908)
			(end -0.849884 1.549908)
			(stroke
				(width 0.1)
				(type default)
			)
			(layer "F.Fab")
		)
		(fp_line
			(start -0.849884 1.549908)
			(end 0.849884 1.549908)
			(stroke
				(width 0.1)
				(type default)
			)
			(layer "F.Fab")
		)
		(fp_line
			(start 0.849884 -1.549908)
			(end -0.849884 -1.549908)
			(stroke
				(width 0.1)
				(type default)
			)
			(layer "F.Fab")
		)
		(fp_line
			(start 0.849884 1.549908)
			(end 0.849884 -1.549908)
			(stroke
				(width 0.1)
				(type default)
			)
			(layer "F.Fab")
		)
		(fp_poly
			(pts
				(xy -2.445766 -1.211326) (xy -1.923034 -0.94996) (xy -2.445766 -0.688594)
			)
			(stroke
				(width 0)
				(type default)
			)
			(fill yes)
			(layer "F.Fab")
		)
		(pad "1" smd rect
			(at -1.124966 -0.94996 90)
			(size 0.6096 0.9652)
			(layers "F.Cu" "F.Mask" "F.Paste")
			(net "P5V_STBY")
		)
		(pad "2" smd rect
			(at -1.124966 0 90)
			(size 0.6096 0.9652)
			(layers "F.Cu" "F.Mask" "F.Paste")
			(net "GND")
		)
		(pad "3" smd rect
			(at -1.124966 0.94996 90)
			(size 0.6096 0.9652)
			(layers "F.Cu" "F.Mask" "F.Paste")
			(net "NCO380_EN")
		)
		(pad "4" smd rect
			(at 1.124966 0.94996 90)
			(size 0.6096 0.9652)
			(layers "F.Cu" "F.Mask" "F.Paste")
			(net "NCP380_FLT_N")
		)
		(pad "5" smd rect
			(at 1.124966 0 90)
			(size 0.6096 0.9652)
			(layers "F.Cu" "F.Mask" "F.Paste")
			(net "NCP380_ILIM")
		)
		(pad "6" smd rect
			(at 1.124966 -0.94996 90)
			(size 0.6096 0.9652)
			(layers "F.Cu" "F.Mask" "F.Paste")
			(net "P5V_STBY_DEBUG")
		)
	)
	(footprint ""
		(layer "F.Cu")
		(at 24.100028 -20.830032)
		(property "Reference" "J2"
			(at -2.8956 -5.02793 0)
			(unlocked yes)
			(layer "F.SilkS")
			(effects
				(font
					(size 0.7874 0.5842)
					(thickness 0.1524)
				)
				(justify left)
			)
		)
		(property "Value" ""
			(at 0 0 0)
			(layer "F.Fab")
			(effects
				(font
					(size 1.27 1.27)
				)
			)
		)
		(duplicate_pad_numbers_are_jumpers no)
		(fp_line
			(start -2.810002 -4.219956)
			(end -2.810002 22.029928)
			(stroke
				(width 0.1524)
				(type default)
			)
			(layer "F.SilkS")
		)
		(fp_line
			(start -2.810002 22.029928)
			(end -2.659888 22.029928)
			(stroke
				(width 0.1524)
				(type default)
			)
			(layer "F.SilkS")
		)
		(fp_line
			(start -2.659888 -3.720084)
			(end 4.459986 -3.720084)
			(stroke
				(width 0.1524)
				(type default)
			)
			(layer "F.SilkS")
		)
		(fp_line
			(start -2.659888 21.480018)
			(end 4.459986 21.480018)
			(stroke
				(width 0.1524)
				(type default)
			)
			(layer "F.SilkS")
		)
		(fp_line
			(start -2.659888 22.029928)
			(end -2.659888 -3.720084)
			(stroke
				(width 0.1524)
				(type default)
			)
			(layer "F.SilkS")
		)
		(fp_line
			(start 4.459986 -3.720084)
			(end 4.459986 22.029928)
			(stroke
				(width 0.1524)
				(type default)
			)
			(layer "F.SilkS")
		)
		(fp_line
			(start 4.459986 22.029928)
			(end -2.659888 22.029928)
			(stroke
				(width 0.1524)
				(type default)
			)
			(layer "F.SilkS")
		)
		(fp_line
			(start 4.459986 22.029928)
			(end 4.6101 22.029928)
			(stroke
				(width 0.1524)
				(type default)
			)
			(layer "F.SilkS")
		)
		(fp_line
			(start 4.6101 -4.219956)
			(end -2.810002 -4.219956)
			(stroke
				(width 0.1524)
				(type default)
			)
			(layer "F.SilkS")
		)
		(fp_line
			(start 4.6101 22.029928)
			(end 4.6101 -4.219956)
			(stroke
				(width 0.1524)
				(type default)
			)
			(layer "F.SilkS")
		)
		(fp_poly
			(pts
				(xy 0.413004 -5.377942) (xy -0.602996 -5.377942) (xy -0.094996 -4.361942)
			)
			(stroke
				(width 0)
				(type default)
			)
			(fill yes)
			(layer "F.SilkS")
		)
		(fp_line
			(start -2.659888 -3.720084)
			(end -2.659888 22.029928)
			(stroke
				(width 0.1)
				(type default)
			)
			(layer "F.Fab")
		)
		(fp_line
			(start -2.659888 22.029928)
			(end 4.459986 22.029928)
			(stroke
				(width 0.1)
				(type default)
			)
			(layer "F.Fab")
		)
		(fp_line
			(start 4.459986 -3.720084)
			(end -2.659888 -3.720084)
			(stroke
				(width 0.1)
				(type default)
			)
			(layer "F.Fab")
		)
		(fp_line
			(start 4.459986 22.029928)
			(end 4.459986 -3.720084)
			(stroke
				(width 0.1)
				(type default)
			)
			(layer "F.Fab")
		)
		(fp_poly
			(pts
				(xy -3.953002 -0.508) (xy -3.953002 0.508) (xy -2.937002 0)
			)
			(stroke
				(width 0)
				(type default)
			)
			(fill yes)
			(layer "F.Fab")
		)
		(pad "1" thru_hole rect
			(at 0 0)
			(size 1.1176 1.1176)
			(drill 0.7112)
			(layers "*.Cu" "*.Mask")
			(remove_unused_layers no)
			(net "P5V_STBY_DEBUG")
			(clearance 0.0508)
			(thermal_gap 0.0508)
			(padstack
				(mode front_inner_back)
				(layer "Inner"
					(shape circle)
					(size 1.1176 1.1176)
					(clearance 0.0508)
				)
				(layer "B.Cu"
					(shape rect)
					(size 1.1176 1.1176)
					(clearance 0.0508)
				)
			)
		)
		(pad "2" thru_hole circle
			(at 0 2.500122)
			(size 1.1176 1.1176)
			(drill 0.7112)
			(layers "*.Cu" "*.Mask")
			(remove_unused_layers no)
			(net "USB2_DEBUG_DN")
			(clearance 0.0508)
			(thermal_gap 0.0508)
		)
		(pad "3" thru_hole circle
			(at 0 4.500118)
			(size 1.1176 1.1176)
			(drill 0.7112)
			(layers "*.Cu" "*.Mask")
			(remove_unused_layers no)
			(net "USB2_DEBUG_DP")
			(clearance 0.0508)
			(thermal_gap 0.0508)
		)
		(pad "4" thru_hole circle
			(at 0 6.999986)
			(size 1.1176 1.1176)
			(drill 0.7112)
			(layers "*.Cu" "*.Mask")
			(remove_unused_layers no)
			(net "GND")
			(clearance 0.0508)
			(thermal_gap 0.0508)
		)
		(pad "5" thru_hole circle
			(at 1.800098 7.500112)
			(size 1.1176 1.1176)
			(drill 0.7112)
			(layers "*.Cu" "*.Mask")
			(remove_unused_layers no)
			(net "SMB_IO_DEBUG_CARD_SCL")
			(clearance 0.0508)
			(thermal_gap 0.0508)
		)
		(pad "6" thru_hole circle
			(at 1.800098 5.500116)
			(size 1.1176 1.1176)
			(drill 0.7112)
			(layers "*.Cu" "*.Mask")
			(remove_unused_layers no)
			(net "SMB_IO_DEBUG_CARD_SDA")
			(clearance 0.0508)
			(thermal_gap 0.0508)
		)
		(pad "7" thru_hole circle
			(at 1.800098 3.50012)
			(size 1.1176 1.1176)
			(drill 0.7112)
			(layers "*.Cu" "*.Mask")
			(remove_unused_layers no)
			(net "PRSNT_DBV2_USB")
			(clearance 0.0508)
			(thermal_gap 0.0508)
		)
		(pad "8" thru_hole circle
			(at 1.800098 1.500124)
			(size 1.1176 1.1176)
			(drill 0.7112)
			(layers "*.Cu" "*.Mask")
			(remove_unused_layers no)
			(net "UART_DEBUG_R_TX")
			(clearance 0.0508)
			(thermal_gap 0.0508)
		)
		(pad "9" thru_hole circle
			(at 1.800098 -0.499872)
			(size 1.1176 1.1176)
			(drill 0.7112)
			(layers "*.Cu" "*.Mask")
			(remove_unused_layers no)
			(net "UART_DEBUG_R_RX")
			(clearance 0.0508)
			(thermal_gap 0.0508)
		)
		(pad "G1" thru_hole oval
			(at -1.810004 8.830056)
			(size 1.3208 2.6162)
			(drill oval 0.8128 2.1082)
			(layers "*.Cu" "*.Mask")
			(remove_unused_layers no)
			(net "GND")
			(clearance 0.127)
			(thermal_gap 0.127)
		)
		(pad "G2" thru_hole oval
			(at 3.610102 8.830056)
			(size 1.3208 1.905)
			(drill oval 0.8128 1.4224)
			(layers "*.Cu" "*.Mask")
			(remove_unused_layers no)
			(net "GND")
			(clearance 0.127)
			(thermal_gap 0.127)
		)
		(pad "G3" thru_hole oval
			(at -1.810004 -1.869948)
			(size 1.3208 1.905)
			(drill oval 0.8128 1.4224)
			(layers "*.Cu" "*.Mask")
			(remove_unused_layers no)
			(net "GND")
			(clearance 0.127)
			(thermal_gap 0.127)
		)
		(pad "G4" thru_hole oval
			(at 3.610102 -1.869948)
			(size 1.3208 2.6162)
			(drill oval 0.8128 2.1082)
			(layers "*.Cu" "*.Mask")
			(remove_unused_layers no)
			(net "GND")
			(clearance 0.127)
			(thermal_gap 0.127)
		)
	)
)
